# T6G (Grand Teton) — schematic netlist excerpt (pin names and nets, part order shuffled) for the footprints in the layout excerpt that follows; sources: Cadence DE-HDL packaged netlist, KiCad conversion of 04192023_DAF0TMB3IC0_F0TG_MB_C_brd_V02_OCP.brd

PR213  Q_RES  2.2 1% CHIP  pkg 0402LF  page 216 : A = PVDDCR_CPU0_P1_PVCC ; B = PVDDCR_SOC_P1_VCC3
C6043  Q_CAP  1UF 25V 10% X6S  pkg C0402  page 177 : A = P3V3_AUX_CPU0_USB_AVDD33 ; B = GND

(kicad_pcb
	(version 20260206)
	(generator "pcbnew")
	(generator_version "10.0")
	(general
		(thickness 1.6)
		(legacy_teardrops no)
	)
	(paper "A4")
	(title_block
		(title "04192023_DAF0TMB3IC0_F0TG_MB_C_brd_V02_OCP.brd")
		(comment 1 "Grand Teton / footprints 7659-7660 of 8354")
	)
	(layers
		(0 "F.Cu" signal "TOP")
		(4 "In1.Cu" signal "GND")
		(6 "In2.Cu" signal "IN1")
		(8 "In3.Cu" signal "GND1")
		(10 "In4.Cu" signal "IN2")
		(12 "In5.Cu" signal "GND2")
		(14 "In6.Cu" signal "IN3")
		(16 "In7.Cu" signal "GND3")
		(18 "In8.Cu" signal "VCC")
		(20 "In9.Cu" signal "VCC1")
		(22 "In10.Cu" signal "GND4")
		(24 "In11.Cu" signal "IN4")
		(26 "In12.Cu" signal "GND5")
		(28 "In13.Cu" signal "IN5")
		(30 "In14.Cu" signal "GND6")
		(32 "In15.Cu" signal "IN6")
		(34 "In16.Cu" signal "GND7")
		(2 "B.Cu" signal "BOTTOM")
		(9 "F.Adhes" user "F.Adhesive")
		(11 "B.Adhes" user "B.Adhesive")
		(13 "F.Paste" user "Package Geometry/Pastemask Top")
		(15 "B.Paste" user "Package Geometry/Pastemask Bottom")
		(5 "F.SilkS" user "Ref Des/Silkscreen Top")
		(7 "B.SilkS" user "Ref Des/Silkscreen Bottom")
		(1 "F.Mask" user "Board Geometry/Soldermask Top")
		(3 "B.Mask" user "Board Geometry/Soldermask Bottom")
		(17 "Dwgs.User" user "User.Drawings")
		(19 "Cmts.User" user "User.Comments")
		(21 "Eco1.User" user "User.Eco1")
		(23 "Eco2.User" user "User.Eco2")
		(25 "Edge.Cuts" user "Board Geometry/Outline")
		(27 "Margin" user)
		(31 "F.CrtYd" user "Package Geometry/Place Bound Top")
		(29 "B.CrtYd" user "Package Geometry/Place Bound Bottom")
		(35 "F.Fab" user "Ref Des/Assembly Top")
		(33 "B.Fab" user "Ref Des/Assembly Bottom")
	)
	(footprint ""
		(layer "B.Cu")
		(at 134.735062 -155.471876 90)
		(property "Reference" "PR213"
			(at 0 0 90)
			(layer "B.SilkS")
			(hide yes)
			(effects
				(font
					(size 1.27 1.27)
				)
				(justify mirror)
			)
		)
		(property "Value" ""
			(at 0 0 90)
			(layer "B.Fab")
			(effects
				(font
					(size 1.27 1.27)
				)
				(justify mirror)
			)
		)
		(duplicate_pad_numbers_are_jumpers no)
		(fp_line
			(start 0.7874 -0.4064)
			(end -0.7874 -0.4064)
			(stroke
				(width 0.1524)
				(type default)
			)
			(layer "B.SilkS")
		)
		(fp_line
			(start -0.7874 -0.4064)
			(end -0.7874 0.4064)
			(stroke
				(width 0.1524)
				(type default)
			)
			(layer "B.SilkS")
		)
		(fp_line
			(start 0.7874 0.4064)
			(end 0.7874 -0.4064)
			(stroke
				(width 0.1524)
				(type default)
			)
			(layer "B.SilkS")
		)
		(fp_line
			(start -0.7874 0.4064)
			(end 0.7874 0.4064)
			(stroke
				(width 0.1524)
				(type default)
			)
			(layer "B.SilkS")
		)
		(fp_line
			(start 0.67945 -0.305054)
			(end 0.12065 -0.305054)
			(stroke
				(width 0.1)
				(type default)
			)
			(layer "B.Fab")
		)
		(fp_line
			(start 0.12065 -0.305054)
			(end 0.12065 -0.2794)
			(stroke
				(width 0.1)
				(type default)
			)
			(layer "B.Fab")
		)
		(fp_line
			(start -0.12065 -0.3048)
			(end -0.67945 -0.3048)
			(stroke
				(width 0.1)
				(type default)
			)
			(layer "B.Fab")
		)
		(fp_line
			(start -0.67945 -0.3048)
			(end -0.67945 0.3048)
			(stroke
				(width 0.1)
				(type default)
			)
			(layer "B.Fab")
		)
		(fp_line
			(start 0.12065 -0.2794)
			(end -0.12065 -0.2794)
			(stroke
				(width 0.1)
				(type default)
			)
			(layer "B.Fab")
		)
		(fp_line
			(start -0.12065 -0.2794)
			(end -0.12065 -0.3048)
			(stroke
				(width 0.1)
				(type default)
			)
			(layer "B.Fab")
		)
		(fp_line
			(start 0.12065 0.2794)
			(end 0.12065 0.3048)
			(stroke
				(width 0.1)
				(type default)
			)
			(layer "B.Fab")
		)
		(fp_line
			(start -0.120396 0.2794)
			(end 0.12065 0.2794)
			(stroke
				(width 0.1)
				(type default)
			)
			(layer "B.Fab")
		)
		(fp_line
			(start 0.67945 0.3048)
			(end 0.67945 -0.305054)
			(stroke
				(width 0.1)
				(type default)
			)
			(layer "B.Fab")
		)
		(fp_line
			(start 0.12065 0.3048)
			(end 0.67945 0.3048)
			(stroke
				(width 0.1)
				(type default)
			)
			(layer "B.Fab")
		)
		(fp_line
			(start -0.120396 0.3048)
			(end -0.120396 0.2794)
			(stroke
				(width 0.1)
				(type default)
			)
			(layer "B.Fab")
		)
		(fp_line
			(start -0.67945 0.3048)
			(end -0.120396 0.3048)
			(stroke
				(width 0.1)
				(type default)
			)
			(layer "B.Fab")
		)
		(pad "1" smd circle
			(at 0.40005 0 270)
			(size 0 0)
			(layers "B.Cu" "B.Mask" "B.Paste")
			(net "PVDDCR_CPU0_P1_PVCC")
		)
		(pad "2" smd circle
			(at -0.40005 0 270)
			(size 0 0)
			(layers "B.Cu" "B.Mask" "B.Paste")
			(net "PVDDCR_SOC_P1_VCC3")
		)
	)
	(footprint ""
		(layer "B.Cu")
		(at 139.28852 -33.526222 90)
		(property "Reference" "C6043"
			(at 0 0 90)
			(layer "B.SilkS")
			(hide yes)
			(effects
				(font
					(size 1.27 1.27)
				)
				(justify mirror)
			)
		)
		(property "Value" ""
			(at 0 0 90)
			(layer "B.Fab")
			(effects
				(font
					(size 1.27 1.27)
				)
				(justify mirror)
			)
		)
		(duplicate_pad_numbers_are_jumpers no)
		(fp_line
			(start 0.7874 -0.4064)
			(end -0.7874 -0.4064)
			(stroke
				(width 0.1524)
				(type default)
			)
			(layer "B.SilkS")
		)
		(fp_line
			(start -0.7874 -0.4064)
			(end -0.7874 0.4064)
			(stroke
				(width 0.1524)
				(type default)
			)
			(layer "B.SilkS")
		)
		(fp_line
			(start 0.7874 0.4064)
			(end 0.7874 -0.4064)
			(stroke
				(width 0.1524)
				(type default)
			)
			(layer "B.SilkS")
		)
		(fp_line
			(start -0.7874 0.4064)
			(end 0.7874 0.4064)
			(stroke
				(width 0.1524)
				(type default)
			)
			(layer "B.SilkS")
		)
		(fp_line
			(start 0.67945 -0.305054)
			(end 0.12065 -0.305054)
			(stroke
				(width 0.1)
				(type default)
			)
			(layer "B.Fab")
		)
		(fp_line
			(start 0.12065 -0.305054)
			(end 0.12065 -0.2794)
			(stroke
				(width 0.1)
				(type default)
			)
			(layer "B.Fab")
		)
		(fp_line
			(start -0.12065 -0.3048)
			(end -0.67945 -0.3048)
			(stroke
				(width 0.1)
				(type default)
			)
			(layer "B.Fab")
		)
		(fp_line
			(start -0.67945 -0.3048)
			(end -0.67945 0.3048)
			(stroke
				(width 0.1)
				(type default)
			)
			(layer "B.Fab")
		)
		(fp_line
			(start 0.12065 -0.2794)
			(end -0.12065 -0.2794)
			(stroke
				(width 0.1)
				(type default)
			)
			(layer "B.Fab")
		)
		(fp_line
			(start -0.12065 -0.2794)
			(end -0.12065 -0.3048)
			(stroke
				(width 0.1)
				(type default)
			)
			(layer "B.Fab")
		)
		(fp_line
			(start 0.12065 0.2794)
			(end 0.12065 0.3048)
			(stroke
				(width 0.1)
				(type default)
			)
			(layer "B.Fab")
		)
		(fp_line
			(start -0.120396 0.2794)
			(end 0.12065 0.2794)
			(stroke
				(width 0.1)
				(type default)
			)
			(layer "B.Fab")
		)
		(fp_line
			(start 0.67945 0.3048)
			(end 0.67945 -0.305054)
			(stroke
				(width 0.1)
				(type default)
			)
			(layer "B.Fab")
		)
		(fp_line
			(start 0.12065 0.3048)
			(end 0.67945 0.3048)
			(stroke
				(width 0.1)
				(type default)
			)
			(layer "B.Fab")
		)
		(fp_line
			(start -0.120396 0.3048)
			(end -0.120396 0.2794)
			(stroke
				(width 0.1)
				(type default)
			)
			(layer "B.Fab")
		)
		(fp_line
			(start -0.67945 0.3048)
			(end -0.120396 0.3048)
			(stroke
				(width 0.1)
				(type default)
			)
			(layer "B.Fab")
		)
		(pad "1" smd circle
			(at 0.40005 0 270)
			(size 0 0)
			(layers "B.Cu" "B.Mask" "B.Paste")
			(net "P3V3_AUX_CPU0_USB_AVDD33")
		)
		(pad "2" smd circle
			(at -0.40005 0 270)
			(size 0 0)
			(layers "B.Cu" "B.Mask" "B.Paste")
			(net "GND")
		)
	)
)
